FILE_TYPE = CONNECTIVITY;
{Allegro Design Entry HDL 16.6-p007 (v16-6-112F) 10/10/2012}
"PAGE_NUMBER" = 167;
0"NC";
1"GND\g";
2"P3V3_STBY\g";
3"GND\g";
4"GND\g";
5"P3V3_STBY\g";
6"P3V3_STBY\g";
7"GND\g";
8"GND\g";
9"GND\g";
10"GND\g";
11"GND\g";
12"P3V3_STBY\g";
13"P3V3_STBY\g";
14"P3V3_STBY\g";
15"P3V3_STBY\g";
16"P3V3_STBY\g";
17"P3V3_STBY\g";
18"P3V3_STBY\g";
19"ISENSE_TMP421_1_BC";
20"ISENSE_TMP421_1_E";
21"PU_TMP421_1_A1";
22"PU_AT24C64_A2";
23"PD_FRU_WP";
24"PU_TMP421_2_A0";
25"PD_TMP421_1_A0";
26"SMB_SENSOR_TMP421_2_SDA";
27"SMB_SENSOR_STBY_LVC3_SDA_R2";
28"PD_TMP421_2_A1";
29"ISENSE_TMP421_2_DXN";
30"ISENSE_TMP421_2_DXP";
31"SMB_SENSOR_STBY_LVC3_SCL_R2";
32"SMB_SENSOR_TMP421_1_SCL";
33"SMB_SENSOR_TMP421_1_SDA";
34"SMB_SENSOR_STBY_LVC3_SDA";
35"SMB_SENSOR_STBY_LVC3_SCL";
36"SMB_SENSOR_STBY_LVC3_SDA";
37"SMB_SENSOR_BMC_STBY_LVC3_SCL";
38"SMB_SENSOR_BMC_STBY_LVC3_SDA";
39"SMB_SENSOR_STBY_LVC3_SDA";
40"SMB_SENSOR_STBY_LVC3_SCL";
41"SMB_SENSOR_STBY_LVC3_SCL";
42"ISENSE_TMP421_2_BC";
43"ISENSE_TMP421_2_E";
44"SMB_SENSOR_TMP421_2_SCL";
45"ISENSE_TMP421_1_DXN";
46"ISENSE_TMP421_1_DXP";
%"TMP421"
"1","(-4000,4450)","0","mstr_analog","I1";
;
CDS_SEC"1"
MATERIAL"IC"
LOCATION"U9B4"
PART_NUMBER"G62962-001"
ROOM"TEMP_SENSORS"
CDS_LOCATION"U9B4"
SEC"1"
BOM_COST"SM_THERM"
SEC_TYPE"TSSOP"
PACK_TYPE"TSSOP"
CDS_LIB"mstr_analog";
"VP"
$PN"8"2;
"A<0>"
$PN"4"25;
"A<1>"
$PN"3"21;
"DXP"
$PN"1"46;
"DXN"
$PN"2"45;
"GND"
$PN"5"3;
"SCL"
$PN"7"32;
"SDA"
$PN"6"33;
%"RES"
"2","(-4775,4075)","0","mstr_discrete","I10";
;
CDS_SEC"1"
MATERIAL"CHIP"
TOLERANCE"1%"
PACK_TYPE"0402"
LOCATION"R9B8"
WATTAGE"1/16W"
VALUE"1.00K"
PART_NUMBER"G21796-026"
CDS_LIB"mstr_discrete"
BOM_COST"SM_THERM"
SEC_TYPE"0402"
SEC"1"
CDS_LOCATION"R9B8"
ROOM"TEMP_SENSORS";
"A"
$PN"1"25;
"B"
$PN"2"1;
%"GND"
"1","(-4775,3850)","0","mstr_symbols","I12";
;
SIZE"1B"
VOLTAGE"0.0V"
CDS_LIB"mstr_symbols"
BODY_TYPE"PLUMBING"
HDL_POWER"GND";
"A\NAC"1;
%"P3V3_STBY"
"1","(-4350,5150)","0","mstr_symbols","I14";
;
VOLTAGE"3.3V"
SIZE"1B"
CDS_LIB"mstr_symbols"
BODY_TYPE"PLUMBING"
HDL_POWER"P3V3_STBY";
"G\NAC"2;
%"GND"
"1","(-3400,3850)","0","mstr_symbols","I15";
;
SIZE"1B"
CDS_LIB"mstr_symbols"
VOLTAGE"0.0V"
BODY_TYPE"PLUMBING"
HDL_POWER"GND";
"A\NAC"3;
%"GND"
"1","(-3225,2400)","0","mstr_symbols","I22";
;
CDS_LIB"mstr_symbols"
SIZE"1B"
VOLTAGE"0.0V"
BODY_TYPE"PLUMBING"
HDL_POWER"GND";
"A\NAC"4;
%"P3V3_STBY"
"1","(-4175,3700)","0","mstr_symbols","I23";
;
CDS_LIB"mstr_symbols"
SIZE"1B"
VOLTAGE"3.3V"
BODY_TYPE"PLUMBING"
HDL_POWER"P3V3_STBY";
"G\NAC"5;
%"CAP"
"1","(-4675,3175)","0","mstr_discrete","I24";
;
CDS_SEC"1"
PART_NUMBER"A36095-025"
PACK_TYPE"0402LF"
VOLTAGE"50V"
TOLERANCE"5%"
VALUE"47.0PF"
LOCATION"C1E19"
MATERIAL"EMPTY"
CDS_LIB"mstr_discrete"
CDS_LOCATION"C1E19"
ROOM"TEMP_SENSORS"
SEC"1"
BOM_COST"SM_THERM"
SEC_TYPE"0402LF";
"A"
$PN"1"30;
"B"
$PN"2"29;
%"RES"
"1","(-5000,3325)","0","mstr_discrete","I25";
;
CDS_SEC"1"
PACK_TYPE"0402"
TOLERANCE"1%"
VALUE"49.9"
WATTAGE"1/16W"
LOCATION"R9R5"
PART_NUMBER"G21796-047"
MATERIAL"CHIP"
CDS_LIB"mstr_discrete"
ROOM"TEMP_SENSORS"
CDS_LOCATION"R9R5"
SEC"1"
BOM_COST"SM_THERM"
SEC_TYPE"0402";
"B"
$PN"2"30;
"A"
$PN"1"43;
%"RES"
"1","(-4975,3000)","0","mstr_discrete","I26";
;
CDS_SEC"1"
PACK_TYPE"0402"
PART_NUMBER"G21796-047"
WATTAGE"1/16W"
TOLERANCE"1%"
LOCATION"R9R6"
MATERIAL"CHIP"
VALUE"49.9"
CDS_LIB"mstr_discrete"
CDS_LOCATION"R9R6"
ROOM"TEMP_SENSORS"
BOM_COST"SM_THERM"
SEC_TYPE"0402"
SEC"1";
"B"
$PN"2"29;
"A"
$PN"1"42;
%"P3V3_STBY"
"1","(-6400,3075)","0","mstr_symbols","I29";
;
VOLTAGE"3.3V"
SIZE"1B"
CDS_LIB"mstr_symbols"
BODY_TYPE"PLUMBING"
HDL_POWER"P3V3_STBY";
"G\NAC"6;
%"TMP421"
"1","(-3825,3000)","0","mstr_analog","I30";
;
CDS_SEC"1"
LOCATION"U1E1"
PART_NUMBER"G62962-001"
MATERIAL"IC"
CDS_LIB"mstr_analog"
ROOM"TEMP_SENSORS"
CDS_LOCATION"U1E1"
SEC"1"
BOM_COST"SM_THERM"
SEC_TYPE"TSSOP"
PACK_TYPE"TSSOP";
"VP"
$PN"8"5;
"A<0>"
$PN"4"24;
"A<1>"
$PN"3"28;
"DXP"
$PN"1"30;
"DXN"
$PN"2"29;
"GND"
$PN"5"4;
"SCL"
$PN"7"44;
"SDA"
$PN"6"26;
%"RES"
"1","(-5050,2850)","0","mstr_discrete","I34";
;
CDS_SEC"1"
LOCATION"R1E9"
PACK_TYPE"0402"
MATERIAL"CHIP"
TOLERANCE"1%"
VALUE"1.00K"
WATTAGE"1/16W"
PART_NUMBER"G21796-026"
CDS_LIB"mstr_discrete"
CDS_LOCATION"R1E9"
ROOM"TEMP_SENSORS"
SEC"1"
BOM_COST"SM_THERM"
SEC_TYPE"0402";
"B"
$PN"2"24;
"A"
$PN"1"6;
%"RES"
"1","(-5475,4150)","0","mstr_discrete","I35";
;
CDS_SEC"1"
MATERIAL"CHIP"
PART_NUMBER"G21796-026"
TOLERANCE"1%"
PACK_TYPE"0402"
VALUE"1.00K"
WATTAGE"1/16W"
LOCATION"R9B6"
BOM_COST"SM_THERM"
ROOM"TEMP_SENSORS"
SEC"1"
SEC_TYPE"0402"
CDS_LIB"mstr_discrete"
CDS_LOCATION"R9B6";
"B"
$PN"2"21;
"A"
$PN"1"15;
%"RES"
"1","(-4650,2900)","0","mstr_discrete","I38";
;
CDS_SEC"1"
PART_NUMBER"G21796-026"
WATTAGE"1/16W"
LOCATION"R1E10"
TOLERANCE"1%"
MATERIAL"CHIP"
VALUE"1.00K"
PACK_TYPE"0402"
CDS_LIB"mstr_discrete"
CDS_LOCATION"R1E10"
ROOM"TEMP_SENSORS"
BOM_COST"SM_THERM"
SEC"1"
SEC_TYPE"0402";
"B"
$PN"2"28;
"A"
$PN"1"6;
%"CAP_A"
"1","(-7700,4350)","0","dev_discrete","I39";
;
LOCATION"C9B7"
VOLTAGE"16V"
TOLERANCE"10%"
MATERIAL"X7R"
PART_NUMBER"A36096-030"
PACK_TYPE"0402V"
VALUE"0.1UF"
CDS_LIB"dev_discrete"
ROOM"TEMP_SENSORS"
CDS_LOCATION"C9B7"
BOM_COST"SM_THERM"
CDS_SEC"1"
SEC_TYPE"0402V"
SEC"1";
"B"
$PN"2"9;
"A"
$PN"1"12;
%"CAP_A"
"1","(-7700,3675)","0","dev_discrete","I41";
;
LOCATION"C9R14"
PACK_TYPE"0402V"
PART_NUMBER"A36096-030"
MATERIAL"X7R"
VALUE"0.1UF"
TOLERANCE"10%"
VOLTAGE"16V"
CDS_LIB"dev_discrete"
ROOM"TEMP_SENSORS"
CDS_LOCATION"C9R14"
BOM_COST"SM_THERM"
CDS_SEC"1"
SEC_TYPE"0402V"
SEC"1";
"B"
$PN"2"7;
"A"
$PN"1"13;
%"CAP_A"
"1","(-1425,2150)","0","dev_discrete","I42";
;
PART_NUMBER"A36096-030"
MATERIAL"X7R"
LOCATION"C9R13"
VALUE"0.1UF"
VOLTAGE"16V"
TOLERANCE"10%"
PACK_TYPE"0402V"
CDS_LIB"dev_discrete"
CDS_LOCATION"C9R13"
CDS_SEC"1"
ROOM"TEMP_SENSORS"
SEC"1"
SEC_TYPE"0402V"
BOM_COST"SM_THERM";
"B"
$PN"2"8;
"A"
$PN"1"16;
%"GND"
"1","(-7700,3350)","0","mstr_symbols","I45";
;
CDS_LIB"mstr_symbols"
VOLTAGE"0.0V"
SIZE"1B"
BODY_TYPE"PLUMBING"
HDL_POWER"GND";
"A\NAC"7;
%"GND"
"1","(-1425,1825)","0","mstr_symbols","I46";
;
SIZE"1B"
VOLTAGE"0.0V"
CDS_LIB"mstr_symbols"
BODY_TYPE"PLUMBING"
HDL_POWER"GND";
"A\NAC"8;
%"GND"
"1","(-7700,4100)","0","mstr_symbols","I47";
;
VOLTAGE"0.0V"
SIZE"1B"
CDS_LIB"mstr_symbols"
BODY_TYPE"PLUMBING"
HDL_POWER"GND";
"A\NAC"9;
%"AT24C64"
"1","(-2700,1650)","0","mstr_memory","I49";
;
CDS_SEC"1"
MATERIAL"IC"
PART_NUMBER"C47049-001"
LOCATION"U8D4"
POWER_GROUP"VCC=P3V3_STBY;GND=GND;"
CDS_LOCATION"U8D4"
CDS_LIB"mstr_memory"
ROOM"TEMP_SENSORS"
PACK_TYPE"SOICLF"
SEC_TYPE"SOICLF"
BOM_COST"SM_THERM"
SEC"1";
"SDA"
$PN"5"27;
"WP"
$PN"7"23;
"SCL"
$PN"6"31;
"A0"
$PN"1"11;
"A1"
$PN"2"11;
"A2"
$PN"3"22;
%"RES"
"1","(-5150,4450)","0","mstr_discrete","I5";
;
CDS_SEC"1"
VALUE"49.9"
MATERIAL"CHIP"
LOCATION"R9B5"
TOLERANCE"1%"
PACK_TYPE"0402"
WATTAGE"1/16W"
PART_NUMBER"G21796-047"
BOM_COST"SM_THERM"
SEC_TYPE"0402"
SEC"1"
ROOM"TEMP_SENSORS"
CDS_LIB"mstr_discrete"
CDS_LOCATION"R9B5";
"B"
$PN"2"45;
"A"
$PN"1"19;
%"RES"
"2","(-3500,1300)","0","mstr_discrete","I50";
;
CDS_SEC"1"
TOLERANCE"1%"
VALUE"1.00K"
LOCATION"R8D27"
PACK_TYPE"0402"
WATTAGE"1/16W"
MATERIAL"CHIP"
PART_NUMBER"G21796-026"
CDS_LIB"mstr_discrete"
SEC"1"
CDS_LOCATION"R8D27"
ROOM"TEMP_SENSORS"
BOM_COST"SM_THERM"
SEC_TYPE"0402";
"A"
$PN"1"23;
"B"
$PN"2"10;
%"GND"
"1","(-3500,1050)","0","mstr_symbols","I52";
;
VOLTAGE"0.0V"
SIZE"1B"
CDS_LIB"mstr_symbols"
BODY_TYPE"PLUMBING"
HDL_POWER"GND";
"A\NAC"10;
%"GND"
"1","(-3075,1050)","0","mstr_symbols","I55";
;
VOLTAGE"0.0V"
CDS_LIB"mstr_symbols"
SIZE"1B"
BODY_TYPE"PLUMBING"
HDL_POWER"GND";
"A\NAC"11;
%"P3V3_STBY"
"1","(-7700,4650)","0","mstr_symbols","I56";
;
VOLTAGE"3.3V"
CDS_LIB"mstr_symbols"
SIZE"1B"
BODY_TYPE"PLUMBING"
HDL_POWER"P3V3_STBY";
"G\NAC"12;
%"P3V3_STBY"
"1","(-7700,3950)","0","mstr_symbols","I57";
;
CDS_LIB"mstr_symbols"
VOLTAGE"3.3V"
SIZE"1B"
BODY_TYPE"PLUMBING"
HDL_POWER"P3V3_STBY";
"G\NAC"13;
%"RES"
"1","(-6725,1450)","0","mstr_discrete","I58";
;
PART_NUMBER"G21796-173"
WATTAGE"1/16W"
PACK_TYPE"0402"
MATERIAL"CHIP"
TOLERANCE"1%"
VALUE"20.0"
LOCATION"R9G15"
CDS_LIB"mstr_discrete"
CDS_LOCATION"R9G15"
$SEC"1"
CDS_SEC"1"
ROOM"SMBUS"
SKU"B"
BOM_COST"SM_CONTROLLER";
"B"
$PN"2"39;
"A"
$PN"1"38;
%"RES"
"1","(-5150,4775)","0","mstr_discrete","I6";
;
CDS_SEC"1"
PACK_TYPE"0402"
TOLERANCE"1%"
VALUE"49.9"
MATERIAL"CHIP"
WATTAGE"1/16W"
PART_NUMBER"G21796-047"
LOCATION"R9B4"
CDS_LIB"mstr_discrete"
CDS_LOCATION"R9B4"
ROOM"TEMP_SENSORS"
SEC"1"
BOM_COST"SM_THERM"
SEC_TYPE"0402";
"B"
$PN"2"46;
"A"
$PN"1"20;
%"CAP"
"1","(-4850,4625)","0","mstr_discrete","I7";
;
CDS_SEC"1"
PART_NUMBER"A36095-025"
VOLTAGE"50V"
LOCATION"C1M4"
VALUE"47.0PF"
TOLERANCE"5%"
MATERIAL"EMPTY"
PACK_TYPE"0402LF"
CDS_LIB"mstr_discrete"
CDS_LOCATION"C1M4"
ROOM"TEMP_SENSORS"
SEC"1"
BOM_COST"SM_THERM"
SEC_TYPE"0402LF";
"A"
$PN"1"46;
"B"
$PN"2"45;
%"RES"
"2","(-3550,1975)","0","mstr_discrete","I70";
;
CDS_SEC"1"
LOCATION"R8D28"
PACK_TYPE"0402"
TOLERANCE"1%"
VALUE"1.00K"
WATTAGE"1/16W"
MATERIAL"CHIP"
PART_NUMBER"G21796-026"
ROOM"TEMP_SENSORS"
CDS_LOCATION"R8D28"
SEC"1"
BOM_COST"SM_THERM"
SEC_TYPE"0402"
CDS_LIB"mstr_discrete";
"A"
$PN"1"14;
"B"
$PN"2"22;
%"P3V3_STBY"
"1","(-3550,2200)","0","mstr_symbols","I71";
;
SIZE"1B"
VOLTAGE"3.3V"
CDS_LIB"mstr_symbols"
BODY_TYPE"PLUMBING"
HDL_POWER"P3V3_STBY";
"G\NAC"14;
%"P3V3_STBY"
"1","(-6375,4250)","0","mstr_symbols","I72";
;
SIZE"1B"
CDS_LIB"mstr_symbols"
VOLTAGE"3.3V"
BODY_TYPE"PLUMBING"
HDL_POWER"P3V3_STBY";
"G\NAC"15;
%"P3V3_STBY"
"1","(-1425,2400)","0","mstr_symbols","I73";
;
VOLTAGE"3.3V"
CDS_LIB"mstr_symbols"
SIZE"1B"
BODY_TYPE"PLUMBING"
HDL_POWER"P3V3_STBY";
"G\NAC"16;
%"RES"
"1","(-2650,4450)","0","mstr_discrete","I74";
;
CDS_SEC"1"
PACK_TYPE"0402"
MATERIAL"CHIP"
PART_NUMBER"G21796-173"
LOCATION"R1M8"
VALUE"20.0"
WATTAGE"1/16W"
TOLERANCE"1%"
CDS_LIB"mstr_discrete"
CDS_LOCATION"R1M8"
ROOM"TEMP_SENSORS"
SEC"1"
SEC_TYPE"0402"
BOM_COST"SM_THERM";
"B"
$PN"2"41;
"A"
$PN"1"32;
%"RES"
"1","(-2300,3000)","0","mstr_discrete","I75";
;
CDS_SEC"1"
PACK_TYPE"0402"
WATTAGE"1/16W"
VALUE"20.0"
TOLERANCE"1%"
LOCATION"R9R7"
PART_NUMBER"G21796-173"
MATERIAL"CHIP"
CDS_LIB"mstr_discrete"
CDS_LOCATION"R9R7"
ROOM"TEMP_SENSORS"
SEC"1"
BOM_COST"SM_THERM"
SEC_TYPE"0402";
"B"
$PN"2"41;
"A"
$PN"1"44;
%"RES"
"1","(-2625,3050)","0","mstr_discrete","I76";
;
CDS_SEC"1"
PART_NUMBER"G21796-173"
LOCATION"R9R8"
TOLERANCE"1%"
VALUE"20.0"
WATTAGE"1/16W"
PACK_TYPE"0402"
MATERIAL"CHIP"
CDS_LIB"mstr_discrete"
ROOM"TEMP_SENSORS"
CDS_LOCATION"R9R8"
SEC"1"
BOM_COST"SM_THERM"
SEC_TYPE"0402";
"B"
$PN"2"36;
"A"
$PN"1"26;
%"RES"
"1","(-6725,1325)","0","mstr_discrete","I77";
;
PACK_TYPE"0402"
WATTAGE"1/16W"
TOLERANCE"1%"
PART_NUMBER"G21796-173"
LOCATION"R9G14"
MATERIAL"CHIP"
VALUE"20.0"
CDS_LOCATION"R9G14"
CDS_LIB"mstr_discrete"
$SEC"1"
CDS_SEC"1"
ROOM"SMBUS"
BOM_COST"SM_CONTROLLER"
SKU"B";
"B"
$PN"2"40;
"A"
$PN"1"37;
%"RES"
"1","(-2950,4500)","0","mstr_discrete","I8";
;
CDS_SEC"1"
PACK_TYPE"0402"
WATTAGE"1/16W"
VALUE"20.0"
MATERIAL"CHIP"
TOLERANCE"1%"
LOCATION"R1M9"
PART_NUMBER"G21796-173"
CDS_LOCATION"R1M9"
CDS_LIB"mstr_discrete"
ROOM"TEMP_SENSORS"
SEC"1"
SEC_TYPE"0402"
BOM_COST"SM_THERM";
"B"
$PN"2"36;
"A"
$PN"1"33;
%"RES"
"2","(-6075,1950)","0","mstr_discrete","I80";
;
CDS_SEC"1"
MATERIAL"CHIP"
WATTAGE"1/16W"
PACK_TYPE"0402"
TOLERANCE"1.0%"
VALUE"665"
LOCATION"R2U38"
PART_NUMBER"G21796-235"
CDS_LIB"mstr_discrete"
CDS_LOCATION"R2U38"
SEC"1"
SEC_TYPE"0402"
ROOM"SMBUS"
BOM_COST"SM_CONTROLLER";
"A"
$PN"1"17;
"B"
$PN"2"40;
%"P3V3_STBY"
"1","(-6075,2200)","0","mstr_symbols","I81";
;
VOLTAGE"3.3V"
CDS_LIB"mstr_symbols"
SIZE"1B"
BODY_TYPE"PLUMBING"
HDL_POWER"P3V3_STBY";
"G\NAC"17;
%"P3V3_STBY"
"1","(-6425,2200)","0","mstr_symbols","I82";
;
VOLTAGE"3.3V"
CDS_LIB"mstr_symbols"
SIZE"1B"
BODY_TYPE"PLUMBING"
HDL_POWER"P3V3_STBY";
"G\NAC"18;
%"RES"
"2","(-6425,1950)","0","mstr_discrete","I83";
;
CDS_SEC"1"
PART_NUMBER"G21796-235"
WATTAGE"1/16W"
MATERIAL"CHIP"
TOLERANCE"1.0%"
PACK_TYPE"0402"
VALUE"665"
LOCATION"R2U39"
CDS_LIB"mstr_discrete"
BOM_COST"SM_CONTROLLER"
SEC_TYPE"0402"
SEC"1"
CDS_LOCATION"R2U39"
ROOM"SMBUS";
"A"
$PN"1"18;
"B"
$PN"2"39;
%"RES"
"1","(-4000,1550)","0","mstr_discrete","I84";
;
CDS_SEC"1"
PART_NUMBER"G21796-173"
PACK_TYPE"0402"
TOLERANCE"1%"
MATERIAL"CHIP"
WATTAGE"1/16W"
VALUE"20.0"
LOCATION"R8D24"
BOM_COST"SM_THERM"
SEC_TYPE"0402"
ROOM"TEMP_SENSORS"
CDS_LIB"mstr_discrete"
SEC"1"
CDS_LOCATION"R8D24";
"B"
$PN"2"31;
"A"
$PN"1"35;
%"RES"
"1","(-1475,1550)","0","mstr_discrete","I85";
;
CDS_SEC"1"
PACK_TYPE"0402"
MATERIAL"CHIP"
TOLERANCE"1%"
VALUE"20.0"
WATTAGE"1/16W"
LOCATION"R8D23"
PART_NUMBER"G21796-173"
ROOM"TEMP_SENSORS"
CDS_LOCATION"R8D23"
BOM_COST"SM_THERM"
CDS_LIB"mstr_discrete"
SEC"1"
SEC_TYPE"0402";
"B"
$PN"2"34;
"A"
$PN"1"27;
%"2SB2907A-B0-00001-GP"
"1","(-5925,4600)","4","w_hdl","I93";
;
CDS_SEC"1"
CDS_LOCATION"Q9B1"
VALUE"2SB2907A-B0-00001-GP"
LOCATION"Q9B1"
PACK_TYPE"DISCRET-GB1"
SEC"1"
SEC_TYPE"DISCRET-GB1"
PART_NUMBER"006.02907.001A"
CDS_LIB"w_hdl"
CDS_LMAN_SYM_OUTLINE"-50,50,50,-50";
"E"
$PN"E"20;
"B"
$PN"B"19;
"C"
$PN"C"19;
%"2SB2907A-B0-00001-GP"
"1","(-5700,3150)","4","w_hdl","I94";
;
CDS_SEC"1"
CDS_LOCATION"Q1E1"
LOCATION"Q1E1"
VALUE"2SB2907A-B0-00001-GP"
PACK_TYPE"DISCRET-GB1"
SEC"1"
SEC_TYPE"DISCRET-GB1"
PART_NUMBER"006.02907.001A"
CDS_LIB"w_hdl"
CDS_LMAN_SYM_OUTLINE"-50,50,50,-50";
"E"
$PN"E"43;
"B"
$PN"B"42;
"C"
$PN"C"42;
END.
